(kicad_pcb
	(version 20260206)
	(generator "pcbnew")
	(generator_version "10.0")
	(general
		(thickness 1.6)
		(legacy_teardrops no)
	)
	(paper "A4")
	(title_block
		(title "9054_F0T_PDB_BD_GPU_F_V04_1213_1550_OCP.brd")
		(comment 1 "Grand Teton / footprints 447-452 of 608")
	)
	(layers
		(0 "F.Cu" signal "TOP")
		(4 "In1.Cu" signal "GND")
		(6 "In2.Cu" signal "IN1")
		(8 "In3.Cu" signal "GND1")
		(10 "In4.Cu" signal "VCC")
		(12 "In5.Cu" signal "VCC1")
		(14 "In6.Cu" signal "GND2")
		(16 "In7.Cu" signal "IN2")
		(18 "In8.Cu" signal "GND3")
		(2 "B.Cu" signal "BOTTOM")
		(9 "F.Adhes" user "F.Adhesive")
		(11 "B.Adhes" user "B.Adhesive")
		(13 "F.Paste" user "Package Geometry/Pastemask Top")
		(15 "B.Paste" user "Package Geometry/Pastemask Bottom")
		(5 "F.SilkS" user "Ref Des/Silkscreen Top")
		(7 "B.SilkS" user "Ref Des/Silkscreen Bottom")
		(1 "F.Mask" user "Board Geometry/Soldermask Top")
		(3 "B.Mask" user "Board Geometry/Soldermask Bottom")
		(17 "Dwgs.User" user "User.Drawings")
		(19 "Cmts.User" user "User.Comments")
		(21 "Eco1.User" user "User.Eco1")
		(23 "Eco2.User" user "User.Eco2")
		(25 "Edge.Cuts" user "Board Geometry/Outline")
		(27 "Margin" user)
		(31 "F.CrtYd" user "Package Geometry/Place Bound Top")
		(29 "B.CrtYd" user "Package Geometry/Place Bound Bottom")
		(35 "F.Fab" user "Ref Des/Assembly Top")
		(33 "B.Fab" user "Ref Des/Assembly Bottom")
	)
	(footprint ""
		(layer "B.Cu")
		(at 272.3134 -62.357 180)
		(property "Reference" "R149"
			(at 0 0 0)
			(layer "B.SilkS")
			(hide yes)
			(effects
				(font
					(size 1.27 1.27)
				)
				(justify mirror)
			)
		)
		(property "Value" ""
			(at 0 0 0)
			(layer "B.Fab")
			(effects
				(font
					(size 1.27 1.27)
				)
				(justify mirror)
			)
		)
		(duplicate_pad_numbers_are_jumpers no)
		(fp_line
			(start 0.7874 0.4064)
			(end 0.7874 -0.4064)
			(stroke
				(width 0.1524)
				(type default)
			)
			(layer "B.SilkS")
		)
		(fp_line
			(start 0.7874 -0.4064)
			(end -0.7874 -0.4064)
			(stroke
				(width 0.1524)
				(type default)
			)
			(layer "B.SilkS")
		)
		(fp_line
			(start -0.7874 0.4064)
			(end 0.7874 0.4064)
			(stroke
				(width 0.1524)
				(type default)
			)
			(layer "B.SilkS")
		)
		(fp_line
			(start -0.7874 -0.4064)
			(end -0.7874 0.4064)
			(stroke
				(width 0.1524)
				(type default)
			)
			(layer "B.SilkS")
		)
		(fp_line
			(start 0.67945 0.3048)
			(end 0.67945 -0.305054)
			(stroke
				(width 0.1)
				(type default)
			)
			(layer "B.Fab")
		)
		(fp_line
			(start 0.67945 -0.305054)
			(end 0.12065 -0.305054)
			(stroke
				(width 0.1)
				(type default)
			)
			(layer "B.Fab")
		)
		(fp_line
			(start 0.12065 0.3048)
			(end 0.67945 0.3048)
			(stroke
				(width 0.1)
				(type default)
			)
			(layer "B.Fab")
		)
		(fp_line
			(start 0.12065 0.2794)
			(end 0.12065 0.3048)
			(stroke
				(width 0.1)
				(type default)
			)
			(layer "B.Fab")
		)
		(fp_line
			(start 0.12065 -0.2794)
			(end -0.12065 -0.2794)
			(stroke
				(width 0.1)
				(type default)
			)
			(layer "B.Fab")
		)
		(fp_line
			(start 0.12065 -0.305054)
			(end 0.12065 -0.2794)
			(stroke
				(width 0.1)
				(type default)
			)
			(layer "B.Fab")
		)
		(fp_line
			(start -0.120396 0.3048)
			(end -0.120396 0.2794)
			(stroke
				(width 0.1)
				(type default)
			)
			(layer "B.Fab")
		)
		(fp_line
			(start -0.120396 0.2794)
			(end 0.12065 0.2794)
			(stroke
				(width 0.1)
				(type default)
			)
			(layer "B.Fab")
		)
		(fp_line
			(start -0.12065 -0.2794)
			(end -0.12065 -0.3048)
			(stroke
				(width 0.1)
				(type default)
			)
			(layer "B.Fab")
		)
		(fp_line
			(start -0.12065 -0.3048)
			(end -0.67945 -0.3048)
			(stroke
				(width 0.1)
				(type default)
			)
			(layer "B.Fab")
		)
		(fp_line
			(start -0.67945 0.3048)
			(end -0.120396 0.3048)
			(stroke
				(width 0.1)
				(type default)
			)
			(layer "B.Fab")
		)
		(fp_line
			(start -0.67945 -0.3048)
			(end -0.67945 0.3048)
			(stroke
				(width 0.1)
				(type default)
			)
			(layer "B.Fab")
		)
		(pad "1" smd circle
			(at 0.40005 0)
			(size 0 0)
			(layers "B.Cu" "B.Mask" "B.Paste")
			(net "PWRGD_P52V_HS1_PG")
		)
		(pad "2" smd circle
			(at -0.40005 0)
			(size 0 0)
			(layers "B.Cu" "B.Mask" "B.Paste")
			(net "GND_FIELD_SIGNAL")
		)
	)
	(footprint ""
		(layer "B.Cu")
		(at 161.336736 -76.962 -90)
		(property "Reference" "PR7009"
			(at 0 0 90)
			(layer "B.SilkS")
			(hide yes)
			(effects
				(font
					(size 1.27 1.27)
				)
				(justify mirror)
			)
		)
		(property "Value" ""
			(at 0 0 90)
			(layer "B.Fab")
			(effects
				(font
					(size 1.27 1.27)
				)
				(justify mirror)
			)
		)
		(duplicate_pad_numbers_are_jumpers no)
		(fp_line
			(start -0.7874 0.4064)
			(end 0.7874 0.4064)
			(stroke
				(width 0.1524)
				(type default)
			)
			(layer "B.SilkS")
		)
		(fp_line
			(start 0.7874 0.4064)
			(end 0.7874 -0.4064)
			(stroke
				(width 0.1524)
				(type default)
			)
			(layer "B.SilkS")
		)
		(fp_line
			(start -0.7874 -0.4064)
			(end -0.7874 0.4064)
			(stroke
				(width 0.1524)
				(type default)
			)
			(layer "B.SilkS")
		)
		(fp_line
			(start 0.7874 -0.4064)
			(end -0.7874 -0.4064)
			(stroke
				(width 0.1524)
				(type default)
			)
			(layer "B.SilkS")
		)
		(fp_line
			(start -0.67945 0.3048)
			(end -0.120396 0.3048)
			(stroke
				(width 0.1)
				(type default)
			)
			(layer "B.Fab")
		)
		(fp_line
			(start -0.120396 0.3048)
			(end -0.120396 0.2794)
			(stroke
				(width 0.1)
				(type default)
			)
			(layer "B.Fab")
		)
		(fp_line
			(start 0.12065 0.3048)
			(end 0.67945 0.3048)
			(stroke
				(width 0.1)
				(type default)
			)
			(layer "B.Fab")
		)
		(fp_line
			(start 0.67945 0.3048)
			(end 0.67945 -0.305054)
			(stroke
				(width 0.1)
				(type default)
			)
			(layer "B.Fab")
		)
		(fp_line
			(start -0.120396 0.2794)
			(end 0.12065 0.2794)
			(stroke
				(width 0.1)
				(type default)
			)
			(layer "B.Fab")
		)
		(fp_line
			(start 0.12065 0.2794)
			(end 0.12065 0.3048)
			(stroke
				(width 0.1)
				(type default)
			)
			(layer "B.Fab")
		)
		(fp_line
			(start -0.12065 -0.2794)
			(end -0.12065 -0.3048)
			(stroke
				(width 0.1)
				(type default)
			)
			(layer "B.Fab")
		)
		(fp_line
			(start 0.12065 -0.2794)
			(end -0.12065 -0.2794)
			(stroke
				(width 0.1)
				(type default)
			)
			(layer "B.Fab")
		)
		(fp_line
			(start -0.67945 -0.3048)
			(end -0.67945 0.3048)
			(stroke
				(width 0.1)
				(type default)
			)
			(layer "B.Fab")
		)
		(fp_line
			(start -0.12065 -0.3048)
			(end -0.67945 -0.3048)
			(stroke
				(width 0.1)
				(type default)
			)
			(layer "B.Fab")
		)
		(fp_line
			(start 0.12065 -0.305054)
			(end 0.12065 -0.2794)
			(stroke
				(width 0.1)
				(type default)
			)
			(layer "B.Fab")
		)
		(fp_line
			(start 0.67945 -0.305054)
			(end 0.12065 -0.305054)
			(stroke
				(width 0.1)
				(type default)
			)
			(layer "B.Fab")
		)
		(pad "1" smd circle
			(at 0.40005 0 90)
			(size 0 0)
			(layers "B.Cu" "B.Mask" "B.Paste")
			(net "HS2_TMR1")
		)
		(pad "2" smd circle
			(at -0.40005 0 90)
			(size 0 0)
			(layers "B.Cu" "B.Mask" "B.Paste")
			(net "HS2_TMR2")
		)
	)
	(footprint ""
		(layer "B.Cu")
		(at 106.045 -54.991 -90)
		(property "Reference" "PR7002"
			(at 0 0 90)
			(layer "B.SilkS")
			(hide yes)
			(effects
				(font
					(size 1.27 1.27)
				)
				(justify mirror)
			)
		)
		(property "Value" ""
			(at 0 0 90)
			(layer "B.Fab")
			(effects
				(font
					(size 1.27 1.27)
				)
				(justify mirror)
			)
		)
		(duplicate_pad_numbers_are_jumpers no)
		(fp_line
			(start -1.2954 0.5842)
			(end 1.2954 0.5842)
			(stroke
				(width 0.1524)
				(type default)
			)
			(layer "B.SilkS")
		)
		(fp_line
			(start 1.2954 0.5842)
			(end 1.2954 -0.5842)
			(stroke
				(width 0.1524)
				(type default)
			)
			(layer "B.SilkS")
		)
		(fp_line
			(start -1.2954 -0.5842)
			(end -1.2954 0.5842)
			(stroke
				(width 0.1524)
				(type default)
			)
			(layer "B.SilkS")
		)
		(fp_line
			(start 1.2954 -0.5842)
			(end -1.2954 -0.5842)
			(stroke
				(width 0.1524)
				(type default)
			)
			(layer "B.SilkS")
		)
		(fp_line
			(start -0.8636 0.4572)
			(end 0.8636 0.4572)
			(stroke
				(width 0.1)
				(type default)
			)
			(layer "B.Fab")
		)
		(fp_line
			(start 0.8636 0.4572)
			(end 0.8636 0.4318)
			(stroke
				(width 0.1)
				(type default)
			)
			(layer "B.Fab")
		)
		(fp_line
			(start 0.8636 0.4318)
			(end 0.8636 0.4064)
			(stroke
				(width 0.1)
				(type default)
			)
			(layer "B.Fab")
		)
		(fp_line
			(start -1.1938 0.4064)
			(end -0.8636 0.4064)
			(stroke
				(width 0.1)
				(type default)
			)
			(layer "B.Fab")
		)
		(fp_line
			(start -0.8636 0.4064)
			(end -0.8636 0.4572)
			(stroke
				(width 0.1)
				(type default)
			)
			(layer "B.Fab")
		)
		(fp_line
			(start 0.8636 0.4064)
			(end 1.1938 0.4064)
			(stroke
				(width 0.1)
				(type default)
			)
			(layer "B.Fab")
		)
		(fp_line
			(start 1.1938 0.4064)
			(end 1.1938 -0.406654)
			(stroke
				(width 0.1)
				(type default)
			)
			(layer "B.Fab")
		)
		(fp_line
			(start -1.1938 -0.406654)
			(end -1.1938 0.4064)
			(stroke
				(width 0.1)
				(type default)
			)
			(layer "B.Fab")
		)
		(fp_line
			(start -0.8636 -0.406654)
			(end -1.1938 -0.406654)
			(stroke
				(width 0.1)
				(type default)
			)
			(layer "B.Fab")
		)
		(fp_line
			(start 0.8636 -0.406654)
			(end 0.8636 -0.4572)
			(stroke
				(width 0.1)
				(type default)
			)
			(layer "B.Fab")
		)
		(fp_line
			(start 1.1938 -0.406654)
			(end 0.8636 -0.406654)
			(stroke
				(width 0.1)
				(type default)
			)
			(layer "B.Fab")
		)
		(fp_line
			(start -0.8636 -0.4572)
			(end -0.8636 -0.406654)
			(stroke
				(width 0.1)
				(type default)
			)
			(layer "B.Fab")
		)
		(fp_line
			(start 0.8636 -0.4572)
			(end -0.8636 -0.4572)
			(stroke
				(width 0.1)
				(type default)
			)
			(layer "B.Fab")
		)
		(pad "1" smd rect
			(at 0.7366 0 180)
			(size 0.7112 0.8128)
			(layers "B.Cu" "B.Mask" "B.Paste")
			(net "P52V_HS2_4287_GATE_R")
		)
		(pad "2" smd rect
			(at -0.7366 0 180)
			(size 0.7112 0.8128)
			(layers "B.Cu" "B.Mask" "B.Paste")
			(net "P52V_HS2_GATE_RC")
		)
	)
	(footprint ""
		(layer "B.Cu")
		(at 161.717736 -68.326)
		(property "Reference" "R5870"
			(at 0 0 0)
			(layer "B.SilkS")
			(hide yes)
			(effects
				(font
					(size 1.27 1.27)
				)
				(justify mirror)
			)
		)
		(property "Value" ""
			(at 0 0 0)
			(layer "B.Fab")
			(effects
				(font
					(size 1.27 1.27)
				)
				(justify mirror)
			)
		)
		(duplicate_pad_numbers_are_jumpers no)
		(fp_line
			(start -0.7874 -0.4064)
			(end -0.7874 0.4064)
			(stroke
				(width 0.1524)
				(type default)
			)
			(layer "B.SilkS")
		)
		(fp_line
			(start -0.7874 0.4064)
			(end 0.7874 0.4064)
			(stroke
				(width 0.1524)
				(type default)
			)
			(layer "B.SilkS")
		)
		(fp_line
			(start 0.7874 -0.4064)
			(end -0.7874 -0.4064)
			(stroke
				(width 0.1524)
				(type default)
			)
			(layer "B.SilkS")
		)
		(fp_line
			(start 0.7874 0.4064)
			(end 0.7874 -0.4064)
			(stroke
				(width 0.1524)
				(type default)
			)
			(layer "B.SilkS")
		)
		(fp_line
			(start -0.67945 -0.3048)
			(end -0.67945 0.3048)
			(stroke
				(width 0.1)
				(type default)
			)
			(layer "B.Fab")
		)
		(fp_line
			(start -0.67945 0.3048)
			(end -0.120396 0.3048)
			(stroke
				(width 0.1)
				(type default)
			)
			(layer "B.Fab")
		)
		(fp_line
			(start -0.12065 -0.3048)
			(end -0.67945 -0.3048)
			(stroke
				(width 0.1)
				(type default)
			)
			(layer "B.Fab")
		)
		(fp_line
			(start -0.12065 -0.2794)
			(end -0.12065 -0.3048)
			(stroke
				(width 0.1)
				(type default)
			)
			(layer "B.Fab")
		)
		(fp_line
			(start -0.120396 0.2794)
			(end 0.12065 0.2794)
			(stroke
				(width 0.1)
				(type default)
			)
			(layer "B.Fab")
		)
		(fp_line
			(start -0.120396 0.3048)
			(end -0.120396 0.2794)
			(stroke
				(width 0.1)
				(type default)
			)
			(layer "B.Fab")
		)
		(fp_line
			(start 0.12065 -0.305054)
			(end 0.12065 -0.2794)
			(stroke
				(width 0.1)
				(type default)
			)
			(layer "B.Fab")
		)
		(fp_line
			(start 0.12065 -0.2794)
			(end -0.12065 -0.2794)
			(stroke
				(width 0.1)
				(type default)
			)
			(layer "B.Fab")
		)
		(fp_line
			(start 0.12065 0.2794)
			(end 0.12065 0.3048)
			(stroke
				(width 0.1)
				(type default)
			)
			(layer "B.Fab")
		)
		(fp_line
			(start 0.12065 0.3048)
			(end 0.67945 0.3048)
			(stroke
				(width 0.1)
				(type default)
			)
			(layer "B.Fab")
		)
		(fp_line
			(start 0.67945 -0.305054)
			(end 0.12065 -0.305054)
			(stroke
				(width 0.1)
				(type default)
			)
			(layer "B.Fab")
		)
		(fp_line
			(start 0.67945 0.3048)
			(end 0.67945 -0.305054)
			(stroke
				(width 0.1)
				(type default)
			)
			(layer "B.Fab")
		)
		(pad "1" smd circle
			(at 0.40005 0 180)
			(size 0 0)
			(layers "B.Cu" "B.Mask" "B.Paste")
			(net "SMB_P52V_PDB_SCL")
		)
		(pad "2" smd circle
			(at -0.40005 0 180)
			(size 0 0)
			(layers "B.Cu" "B.Mask" "B.Paste")
			(net "SMB_P52V_PDB_SCL_R4")
		)
	)
	(footprint ""
		(layer "B.Cu")
		(at 170.226736 -68.326 180)
		(property "Reference" "PR7027"
			(at 0 0 0)
			(layer "B.SilkS")
			(hide yes)
			(effects
				(font
					(size 1.27 1.27)
				)
				(justify mirror)
			)
		)
		(property "Value" ""
			(at 0 0 0)
			(layer "B.Fab")
			(effects
				(font
					(size 1.27 1.27)
				)
				(justify mirror)
			)
		)
		(duplicate_pad_numbers_are_jumpers no)
		(fp_line
			(start 0.7874 0.4064)
			(end 0.7874 -0.4064)
			(stroke
				(width 0.1524)
				(type default)
			)
			(layer "B.SilkS")
		)
		(fp_line
			(start 0.7874 -0.4064)
			(end -0.7874 -0.4064)
			(stroke
				(width 0.1524)
				(type default)
			)
			(layer "B.SilkS")
		)
		(fp_line
			(start -0.7874 0.4064)
			(end 0.7874 0.4064)
			(stroke
				(width 0.1524)
				(type default)
			)
			(layer "B.SilkS")
		)
		(fp_line
			(start -0.7874 -0.4064)
			(end -0.7874 0.4064)
			(stroke
				(width 0.1524)
				(type default)
			)
			(layer "B.SilkS")
		)
		(fp_line
			(start 0.67945 0.3048)
			(end 0.67945 -0.305054)
			(stroke
				(width 0.1)
				(type default)
			)
			(layer "B.Fab")
		)
		(fp_line
			(start 0.67945 -0.305054)
			(end 0.12065 -0.305054)
			(stroke
				(width 0.1)
				(type default)
			)
			(layer "B.Fab")
		)
		(fp_line
			(start 0.12065 0.3048)
			(end 0.67945 0.3048)
			(stroke
				(width 0.1)
				(type default)
			)
			(layer "B.Fab")
		)
		(fp_line
			(start 0.12065 0.2794)
			(end 0.12065 0.3048)
			(stroke
				(width 0.1)
				(type default)
			)
			(layer "B.Fab")
		)
		(fp_line
			(start 0.12065 -0.2794)
			(end -0.12065 -0.2794)
			(stroke
				(width 0.1)
				(type default)
			)
			(layer "B.Fab")
		)
		(fp_line
			(start 0.12065 -0.305054)
			(end 0.12065 -0.2794)
			(stroke
				(width 0.1)
				(type default)
			)
			(layer "B.Fab")
		)
		(fp_line
			(start -0.120396 0.3048)
			(end -0.120396 0.2794)
			(stroke
				(width 0.1)
				(type default)
			)
			(layer "B.Fab")
		)
		(fp_line
			(start -0.120396 0.2794)
			(end 0.12065 0.2794)
			(stroke
				(width 0.1)
				(type default)
			)
			(layer "B.Fab")
		)
		(fp_line
			(start -0.12065 -0.2794)
			(end -0.12065 -0.3048)
			(stroke
				(width 0.1)
				(type default)
			)
			(layer "B.Fab")
		)
		(fp_line
			(start -0.12065 -0.3048)
			(end -0.67945 -0.3048)
			(stroke
				(width 0.1)
				(type default)
			)
			(layer "B.Fab")
		)
		(fp_line
			(start -0.67945 0.3048)
			(end -0.120396 0.3048)
			(stroke
				(width 0.1)
				(type default)
			)
			(layer "B.Fab")
		)
		(fp_line
			(start -0.67945 -0.3048)
			(end -0.67945 0.3048)
			(stroke
				(width 0.1)
				(type default)
			)
			(layer "B.Fab")
		)
		(pad "1" smd circle
			(at 0.40005 0)
			(size 0 0)
			(layers "B.Cu" "B.Mask" "B.Paste")
			(net "P52V_HS2_ISTART")
		)
		(pad "2" smd circle
			(at -0.40005 0)
			(size 0 0)
			(layers "B.Cu" "B.Mask" "B.Paste")
			(net "P52V_HS2_VCAP")
		)
	)
	(footprint ""
		(layer "B.Cu")
		(at 106.1974 -45.7454 180)
		(property "Reference" "PC593"
			(at 0 0 0)
			(layer "B.SilkS")
			(hide yes)
			(effects
				(font
					(size 1.27 1.27)
				)
				(justify mirror)
			)
		)
		(property "Value" ""
			(at 0 0 0)
			(layer "B.Fab")
			(effects
				(font
					(size 1.27 1.27)
				)
				(justify mirror)
			)
		)
		(duplicate_pad_numbers_are_jumpers no)
		(fp_line
			(start 1.2954 0.5842)
			(end 1.2954 -0.5842)
			(stroke
				(width 0.1524)
				(type default)
			)
			(layer "B.SilkS")
		)
		(fp_line
			(start 1.2954 -0.5842)
			(end -1.2954 -0.5842)
			(stroke
				(width 0.1524)
				(type default)
			)
			(layer "B.SilkS")
		)
		(fp_line
			(start -1.2954 0.5842)
			(end 1.2954 0.5842)
			(stroke
				(width 0.1524)
				(type default)
			)
			(layer "B.SilkS")
		)
		(fp_line
			(start -1.2954 -0.5842)
			(end -1.2954 0.5842)
			(stroke
				(width 0.1524)
				(type default)
			)
			(layer "B.SilkS")
		)
		(fp_line
			(start 1.1938 0.4064)
			(end 1.1938 -0.4064)
			(stroke
				(width 0.1)
				(type default)
			)
			(layer "B.Fab")
		)
		(fp_line
			(start 1.1938 -0.4064)
			(end 0.8636 -0.4064)
			(stroke
				(width 0.1)
				(type default)
			)
			(layer "B.Fab")
		)
		(fp_line
			(start 0.8636 0.4572)
			(end 0.8636 0.4064)
			(stroke
				(width 0.1)
				(type default)
			)
			(layer "B.Fab")
		)
		(fp_line
			(start 0.8636 0.4064)
			(end 1.1938 0.4064)
			(stroke
				(width 0.1)
				(type default)
			)
			(layer "B.Fab")
		)
		(fp_line
			(start 0.8636 -0.4064)
			(end 0.8636 -0.4572)
			(stroke
				(width 0.1)
				(type default)
			)
			(layer "B.Fab")
		)
		(fp_line
			(start 0.8636 -0.4572)
			(end -0.8636 -0.4572)
			(stroke
				(width 0.1)
				(type default)
			)
			(layer "B.Fab")
		)
		(fp_line
			(start -0.8636 0.4572)
			(end 0.8636 0.4572)
			(stroke
				(width 0.1)
				(type default)
			)
			(layer "B.Fab")
		)
		(fp_line
			(start -0.8636 0.4064)
			(end -0.8636 0.4572)
			(stroke
				(width 0.1)
				(type default)
			)
			(layer "B.Fab")
		)
		(fp_line
			(start -0.8636 -0.4064)
			(end -1.1938 -0.4064)
			(stroke
				(width 0.1)
				(type default)
			)
			(layer "B.Fab")
		)
		(fp_line
			(start -0.8636 -0.4572)
			(end -0.8636 -0.4064)
			(stroke
				(width 0.1)
				(type default)
			)
			(layer "B.Fab")
		)
		(fp_line
			(start -1.1938 0.4064)
			(end -0.8636 0.4064)
			(stroke
				(width 0.1)
				(type default)
			)
			(layer "B.Fab")
		)
		(fp_line
			(start -1.1938 -0.4064)
			(end -1.1938 0.4064)
			(stroke
				(width 0.1)
				(type default)
			)
			(layer "B.Fab")
		)
		(pad "1" smd rect
			(at 0.7366 0 90)
			(size 0.7112 0.8128)
			(layers "B.Cu" "B.Mask" "B.Paste")
			(net "GND")
		)
		(pad "2" smd rect
			(at -0.7366 0 90)
			(size 0.7112 0.8128)
			(layers "B.Cu" "B.Mask" "B.Paste")
			(net "P52V_HS2_GATE2_R1")
		)
	)
)
